FILE_TYPE=LIBRARY_PARTS;
primitive 'RT9059GQW';
  pin
    'PGOOD':
      PIN_NUMBER='(5)';
      OUTPUT_LOAD='(1.0,-1.0)';
    'EN':
      PIN_NUMBER='(6)';
      INPUT_LOAD='(-0.01,0.01)';
    'ADJ':
      PIN_NUMBER='(4)';
      INPUT_LOAD='(-0.01,0.01)';
    'VOUT1':
      PIN_NUMBER='(1)';
      OUTPUT_LOAD='(1.0,-1.0)';
    'VIN1':
      PIN_NUMBER='(7)';
      INPUT_LOAD='(-0.01,0.01)';
    'VDD':
      PIN_NUMBER='(10)';
      INPUT_LOAD='(-0.01,0.01)';
    'EP':
      PIN_NUMBER='(TH)';
      PINUSE='POWER';
      NO_LOAD_CHECK='Both';
      NO_IO_CHECK='Both';
      NO_ASSERT_CHECK='TRUE';
      NO_DIR_CHECK='TRUE';
      ALLOW_CONNECT='TRUE';
    'VOUT2':
      PIN_NUMBER='(2)';
      OUTPUT_LOAD='(1.0,-1.0)';
    'VOUT3':
      PIN_NUMBER='(3)';
      OUTPUT_LOAD='(1.0,-1.0)';
    'VIN2':
      PIN_NUMBER='(8)';
      INPUT_LOAD='(-0.01,0.01)';
    'VIN3':
      PIN_NUMBER='(9)';
      INPUT_LOAD='(-0.01,0.01)';
  end_pin;
  body
    PART_NAME='RT9059GQW';
    BODY_NAME='RT9059GQW';
    PHYS_DES_PREFIX='U';
    CLASS='IC';
  end_body;
end_primitive;

END.
